(kicad_pcb
	(version 20260206)
	(generator "pcbnew")
	(generator_version "10.0")
	(general
		(thickness 1.6)
		(legacy_teardrops no)
	)
	(paper "A4")
	(title_block
		(title "04192023_DAF0TMB3IC0_F0TG_MB_C_brd_V02_OCP.brd")
		(comment 1 "Grand Teton / footprints 6751-6756 of 8354")
	)
	(layers
		(0 "F.Cu" signal "TOP")
		(4 "In1.Cu" signal "GND")
		(6 "In2.Cu" signal "IN1")
		(8 "In3.Cu" signal "GND1")
		(10 "In4.Cu" signal "IN2")
		(12 "In5.Cu" signal "GND2")
		(14 "In6.Cu" signal "IN3")
		(16 "In7.Cu" signal "GND3")
		(18 "In8.Cu" signal "VCC")
		(20 "In9.Cu" signal "VCC1")
		(22 "In10.Cu" signal "GND4")
		(24 "In11.Cu" signal "IN4")
		(26 "In12.Cu" signal "GND5")
		(28 "In13.Cu" signal "IN5")
		(30 "In14.Cu" signal "GND6")
		(32 "In15.Cu" signal "IN6")
		(34 "In16.Cu" signal "GND7")
		(2 "B.Cu" signal "BOTTOM")
		(9 "F.Adhes" user "F.Adhesive")
		(11 "B.Adhes" user "B.Adhesive")
		(13 "F.Paste" user "Package Geometry/Pastemask Top")
		(15 "B.Paste" user "Package Geometry/Pastemask Bottom")
		(5 "F.SilkS" user "Ref Des/Silkscreen Top")
		(7 "B.SilkS" user "Ref Des/Silkscreen Bottom")
		(1 "F.Mask" user "Board Geometry/Soldermask Top")
		(3 "B.Mask" user "Board Geometry/Soldermask Bottom")
		(17 "Dwgs.User" user "User.Drawings")
		(19 "Cmts.User" user "User.Comments")
		(21 "Eco1.User" user "User.Eco1")
		(23 "Eco2.User" user "User.Eco2")
		(25 "Edge.Cuts" user "Board Geometry/Outline")
		(27 "Margin" user)
		(31 "F.CrtYd" user "Package Geometry/Place Bound Top")
		(29 "B.CrtYd" user "Package Geometry/Place Bound Bottom")
		(35 "F.Fab" user "Ref Des/Assembly Top")
		(33 "B.Fab" user "Ref Des/Assembly Bottom")
	)
	(footprint ""
		(layer "B.Cu")
		(at 361.899454 -266.00531)
		(property "Reference" "C2646"
			(at 0 0 0)
			(layer "B.SilkS")
			(hide yes)
			(effects
				(font
					(size 1.27 1.27)
				)
				(justify mirror)
			)
		)
		(property "Value" ""
			(at 0 0 0)
			(layer "B.Fab")
			(effects
				(font
					(size 1.27 1.27)
				)
				(justify mirror)
			)
		)
		(duplicate_pad_numbers_are_jumpers no)
		(fp_line
			(start -0.7874 -0.4064)
			(end -0.7874 0.4064)
			(stroke
				(width 0.1524)
				(type default)
			)
			(layer "B.SilkS")
		)
		(fp_line
			(start -0.7874 0.4064)
			(end 0.7874 0.4064)
			(stroke
				(width 0.1524)
				(type default)
			)
			(layer "B.SilkS")
		)
		(fp_line
			(start 0.7874 -0.4064)
			(end -0.7874 -0.4064)
			(stroke
				(width 0.1524)
				(type default)
			)
			(layer "B.SilkS")
		)
		(fp_line
			(start 0.7874 0.4064)
			(end 0.7874 -0.4064)
			(stroke
				(width 0.1524)
				(type default)
			)
			(layer "B.SilkS")
		)
		(fp_line
			(start -0.67945 -0.3048)
			(end -0.67945 0.3048)
			(stroke
				(width 0.1)
				(type default)
			)
			(layer "B.Fab")
		)
		(fp_line
			(start -0.67945 0.3048)
			(end -0.120396 0.3048)
			(stroke
				(width 0.1)
				(type default)
			)
			(layer "B.Fab")
		)
		(fp_line
			(start -0.12065 -0.3048)
			(end -0.67945 -0.3048)
			(stroke
				(width 0.1)
				(type default)
			)
			(layer "B.Fab")
		)
		(fp_line
			(start -0.12065 -0.2794)
			(end -0.12065 -0.3048)
			(stroke
				(width 0.1)
				(type default)
			)
			(layer "B.Fab")
		)
		(fp_line
			(start -0.120396 0.2794)
			(end 0.12065 0.2794)
			(stroke
				(width 0.1)
				(type default)
			)
			(layer "B.Fab")
		)
		(fp_line
			(start -0.120396 0.3048)
			(end -0.120396 0.2794)
			(stroke
				(width 0.1)
				(type default)
			)
			(layer "B.Fab")
		)
		(fp_line
			(start 0.12065 -0.305054)
			(end 0.12065 -0.2794)
			(stroke
				(width 0.1)
				(type default)
			)
			(layer "B.Fab")
		)
		(fp_line
			(start 0.12065 -0.2794)
			(end -0.12065 -0.2794)
			(stroke
				(width 0.1)
				(type default)
			)
			(layer "B.Fab")
		)
		(fp_line
			(start 0.12065 0.2794)
			(end 0.12065 0.3048)
			(stroke
				(width 0.1)
				(type default)
			)
			(layer "B.Fab")
		)
		(fp_line
			(start 0.12065 0.3048)
			(end 0.67945 0.3048)
			(stroke
				(width 0.1)
				(type default)
			)
			(layer "B.Fab")
		)
		(fp_line
			(start 0.67945 -0.305054)
			(end 0.12065 -0.305054)
			(stroke
				(width 0.1)
				(type default)
			)
			(layer "B.Fab")
		)
		(fp_line
			(start 0.67945 0.3048)
			(end 0.67945 -0.305054)
			(stroke
				(width 0.1)
				(type default)
			)
			(layer "B.Fab")
		)
		(pad "1" smd circle
			(at 0.40005 0 180)
			(size 0 0)
			(layers "B.Cu" "B.Mask" "B.Paste")
			(net "PVDD11_S3_P0")
		)
		(pad "2" smd circle
			(at -0.40005 0 180)
			(size 0 0)
			(layers "B.Cu" "B.Mask" "B.Paste")
			(net "GND")
		)
	)
	(footprint ""
		(layer "B.Cu")
		(at 447.563748 -10.567162 90)
		(property "Reference" "R32"
			(at 0 0 90)
			(layer "B.SilkS")
			(hide yes)
			(effects
				(font
					(size 1.27 1.27)
				)
				(justify mirror)
			)
		)
		(property "Value" ""
			(at 0 0 90)
			(layer "B.Fab")
			(effects
				(font
					(size 1.27 1.27)
				)
				(justify mirror)
			)
		)
		(duplicate_pad_numbers_are_jumpers no)
		(fp_line
			(start 0.7874 -0.4064)
			(end -0.7874 -0.4064)
			(stroke
				(width 0.1524)
				(type default)
			)
			(layer "B.SilkS")
		)
		(fp_line
			(start -0.7874 -0.4064)
			(end -0.7874 0.4064)
			(stroke
				(width 0.1524)
				(type default)
			)
			(layer "B.SilkS")
		)
		(fp_line
			(start 0.7874 0.4064)
			(end 0.7874 -0.4064)
			(stroke
				(width 0.1524)
				(type default)
			)
			(layer "B.SilkS")
		)
		(fp_line
			(start -0.7874 0.4064)
			(end 0.7874 0.4064)
			(stroke
				(width 0.1524)
				(type default)
			)
			(layer "B.SilkS")
		)
		(fp_line
			(start 0.67945 -0.305054)
			(end 0.12065 -0.305054)
			(stroke
				(width 0.1)
				(type default)
			)
			(layer "B.Fab")
		)
		(fp_line
			(start 0.12065 -0.305054)
			(end 0.12065 -0.2794)
			(stroke
				(width 0.1)
				(type default)
			)
			(layer "B.Fab")
		)
		(fp_line
			(start -0.12065 -0.3048)
			(end -0.67945 -0.3048)
			(stroke
				(width 0.1)
				(type default)
			)
			(layer "B.Fab")
		)
		(fp_line
			(start -0.67945 -0.3048)
			(end -0.67945 0.3048)
			(stroke
				(width 0.1)
				(type default)
			)
			(layer "B.Fab")
		)
		(fp_line
			(start 0.12065 -0.2794)
			(end -0.12065 -0.2794)
			(stroke
				(width 0.1)
				(type default)
			)
			(layer "B.Fab")
		)
		(fp_line
			(start -0.12065 -0.2794)
			(end -0.12065 -0.3048)
			(stroke
				(width 0.1)
				(type default)
			)
			(layer "B.Fab")
		)
		(fp_line
			(start 0.12065 0.2794)
			(end 0.12065 0.3048)
			(stroke
				(width 0.1)
				(type default)
			)
			(layer "B.Fab")
		)
		(fp_line
			(start -0.120396 0.2794)
			(end 0.12065 0.2794)
			(stroke
				(width 0.1)
				(type default)
			)
			(layer "B.Fab")
		)
		(fp_line
			(start 0.67945 0.3048)
			(end 0.67945 -0.305054)
			(stroke
				(width 0.1)
				(type default)
			)
			(layer "B.Fab")
		)
		(fp_line
			(start 0.12065 0.3048)
			(end 0.67945 0.3048)
			(stroke
				(width 0.1)
				(type default)
			)
			(layer "B.Fab")
		)
		(fp_line
			(start -0.120396 0.3048)
			(end -0.120396 0.2794)
			(stroke
				(width 0.1)
				(type default)
			)
			(layer "B.Fab")
		)
		(fp_line
			(start -0.67945 0.3048)
			(end -0.120396 0.3048)
			(stroke
				(width 0.1)
				(type default)
			)
			(layer "B.Fab")
		)
		(pad "1" smd circle
			(at 0.40005 0 270)
			(size 0 0)
			(layers "B.Cu" "B.Mask" "B.Paste")
			(net "OCP_SFF_ID0")
		)
		(pad "2" smd circle
			(at -0.40005 0 270)
			(size 0 0)
			(layers "B.Cu" "B.Mask" "B.Paste")
			(net "GND")
		)
	)
	(footprint ""
		(layer "B.Cu")
		(at 359.994454 -264.86231)
		(property "Reference" "C2623"
			(at 0 0 0)
			(layer "B.SilkS")
			(hide yes)
			(effects
				(font
					(size 1.27 1.27)
				)
				(justify mirror)
			)
		)
		(property "Value" ""
			(at 0 0 0)
			(layer "B.Fab")
			(effects
				(font
					(size 1.27 1.27)
				)
				(justify mirror)
			)
		)
		(duplicate_pad_numbers_are_jumpers no)
		(fp_line
			(start -0.7874 -0.4064)
			(end -0.7874 0.4064)
			(stroke
				(width 0.1524)
				(type default)
			)
			(layer "B.SilkS")
		)
		(fp_line
			(start -0.7874 0.4064)
			(end 0.7874 0.4064)
			(stroke
				(width 0.1524)
				(type default)
			)
			(layer "B.SilkS")
		)
		(fp_line
			(start 0.7874 -0.4064)
			(end -0.7874 -0.4064)
			(stroke
				(width 0.1524)
				(type default)
			)
			(layer "B.SilkS")
		)
		(fp_line
			(start 0.7874 0.4064)
			(end 0.7874 -0.4064)
			(stroke
				(width 0.1524)
				(type default)
			)
			(layer "B.SilkS")
		)
		(fp_line
			(start -0.67945 -0.3048)
			(end -0.67945 0.3048)
			(stroke
				(width 0.1)
				(type default)
			)
			(layer "B.Fab")
		)
		(fp_line
			(start -0.67945 0.3048)
			(end -0.120396 0.3048)
			(stroke
				(width 0.1)
				(type default)
			)
			(layer "B.Fab")
		)
		(fp_line
			(start -0.12065 -0.3048)
			(end -0.67945 -0.3048)
			(stroke
				(width 0.1)
				(type default)
			)
			(layer "B.Fab")
		)
		(fp_line
			(start -0.12065 -0.2794)
			(end -0.12065 -0.3048)
			(stroke
				(width 0.1)
				(type default)
			)
			(layer "B.Fab")
		)
		(fp_line
			(start -0.120396 0.2794)
			(end 0.12065 0.2794)
			(stroke
				(width 0.1)
				(type default)
			)
			(layer "B.Fab")
		)
		(fp_line
			(start -0.120396 0.3048)
			(end -0.120396 0.2794)
			(stroke
				(width 0.1)
				(type default)
			)
			(layer "B.Fab")
		)
		(fp_line
			(start 0.12065 -0.305054)
			(end 0.12065 -0.2794)
			(stroke
				(width 0.1)
				(type default)
			)
			(layer "B.Fab")
		)
		(fp_line
			(start 0.12065 -0.2794)
			(end -0.12065 -0.2794)
			(stroke
				(width 0.1)
				(type default)
			)
			(layer "B.Fab")
		)
		(fp_line
			(start 0.12065 0.2794)
			(end 0.12065 0.3048)
			(stroke
				(width 0.1)
				(type default)
			)
			(layer "B.Fab")
		)
		(fp_line
			(start 0.12065 0.3048)
			(end 0.67945 0.3048)
			(stroke
				(width 0.1)
				(type default)
			)
			(layer "B.Fab")
		)
		(fp_line
			(start 0.67945 -0.305054)
			(end 0.12065 -0.305054)
			(stroke
				(width 0.1)
				(type default)
			)
			(layer "B.Fab")
		)
		(fp_line
			(start 0.67945 0.3048)
			(end 0.67945 -0.305054)
			(stroke
				(width 0.1)
				(type default)
			)
			(layer "B.Fab")
		)
		(pad "1" smd circle
			(at 0.40005 0 180)
			(size 0 0)
			(layers "B.Cu" "B.Mask" "B.Paste")
			(net "PVDD11_S3_P0")
		)
		(pad "2" smd circle
			(at -0.40005 0 180)
			(size 0 0)
			(layers "B.Cu" "B.Mask" "B.Paste")
			(net "GND")
		)
	)
	(footprint ""
		(layer "B.Cu")
		(at 439.020966 -427.089824 180)
		(property "Reference" "R643"
			(at 0 0 0)
			(layer "B.SilkS")
			(hide yes)
			(effects
				(font
					(size 1.27 1.27)
				)
				(justify mirror)
			)
		)
		(property "Value" ""
			(at 0 0 0)
			(layer "B.Fab")
			(effects
				(font
					(size 1.27 1.27)
				)
				(justify mirror)
			)
		)
		(duplicate_pad_numbers_are_jumpers no)
		(fp_line
			(start 0.7874 0.4064)
			(end 0.7874 -0.4064)
			(stroke
				(width 0.1524)
				(type default)
			)
			(layer "B.SilkS")
		)
		(fp_line
			(start 0.7874 -0.4064)
			(end -0.7874 -0.4064)
			(stroke
				(width 0.1524)
				(type default)
			)
			(layer "B.SilkS")
		)
		(fp_line
			(start -0.7874 0.4064)
			(end 0.7874 0.4064)
			(stroke
				(width 0.1524)
				(type default)
			)
			(layer "B.SilkS")
		)
		(fp_line
			(start -0.7874 -0.4064)
			(end -0.7874 0.4064)
			(stroke
				(width 0.1524)
				(type default)
			)
			(layer "B.SilkS")
		)
		(fp_line
			(start 0.67945 0.3048)
			(end 0.67945 -0.305054)
			(stroke
				(width 0.1)
				(type default)
			)
			(layer "B.Fab")
		)
		(fp_line
			(start 0.67945 -0.305054)
			(end 0.12065 -0.305054)
			(stroke
				(width 0.1)
				(type default)
			)
			(layer "B.Fab")
		)
		(fp_line
			(start 0.12065 0.3048)
			(end 0.67945 0.3048)
			(stroke
				(width 0.1)
				(type default)
			)
			(layer "B.Fab")
		)
		(fp_line
			(start 0.12065 0.2794)
			(end 0.12065 0.3048)
			(stroke
				(width 0.1)
				(type default)
			)
			(layer "B.Fab")
		)
		(fp_line
			(start 0.12065 -0.2794)
			(end -0.12065 -0.2794)
			(stroke
				(width 0.1)
				(type default)
			)
			(layer "B.Fab")
		)
		(fp_line
			(start 0.12065 -0.305054)
			(end 0.12065 -0.2794)
			(stroke
				(width 0.1)
				(type default)
			)
			(layer "B.Fab")
		)
		(fp_line
			(start -0.120396 0.3048)
			(end -0.120396 0.2794)
			(stroke
				(width 0.1)
				(type default)
			)
			(layer "B.Fab")
		)
		(fp_line
			(start -0.120396 0.2794)
			(end 0.12065 0.2794)
			(stroke
				(width 0.1)
				(type default)
			)
			(layer "B.Fab")
		)
		(fp_line
			(start -0.12065 -0.2794)
			(end -0.12065 -0.3048)
			(stroke
				(width 0.1)
				(type default)
			)
			(layer "B.Fab")
		)
		(fp_line
			(start -0.12065 -0.3048)
			(end -0.67945 -0.3048)
			(stroke
				(width 0.1)
				(type default)
			)
			(layer "B.Fab")
		)
		(fp_line
			(start -0.67945 0.3048)
			(end -0.120396 0.3048)
			(stroke
				(width 0.1)
				(type default)
			)
			(layer "B.Fab")
		)
		(fp_line
			(start -0.67945 -0.3048)
			(end -0.67945 0.3048)
			(stroke
				(width 0.1)
				(type default)
			)
			(layer "B.Fab")
		)
		(pad "1" smd circle
			(at 0.40005 0)
			(size 0 0)
			(layers "B.Cu" "B.Mask" "B.Paste")
			(net "P3V3_AUX")
		)
		(pad "2" smd circle
			(at -0.40005 0)
			(size 0 0)
			(layers "B.Cu" "B.Mask" "B.Paste")
			(net "PWRGD_P0V9_RETIMER_CPU0_R")
		)
	)
	(footprint ""
		(layer "B.Cu")
		(at 401.650962 -316.917578 180)
		(property "Reference" "Y3"
			(at 1.188974 2.370836 0)
			(unlocked yes)
			(layer "B.SilkS")
			(effects
				(font
					(size 0.7874 0.5842)
					(thickness 0.1524)
				)
				(justify left mirror)
			)
		)
		(property "Value" ""
			(at 0 0 0)
			(layer "B.Fab")
			(effects
				(font
					(size 1.27 1.27)
				)
				(justify mirror)
			)
		)
		(duplicate_pad_numbers_are_jumpers no)
		(fp_line
			(start 1.905 1.0414)
			(end -1.905 1.0414)
			(stroke
				(width 0.1524)
				(type default)
			)
			(layer "B.SilkS")
		)
		(fp_line
			(start 1.905 -1.0414)
			(end 1.905 1.0414)
			(stroke
				(width 0.1524)
				(type default)
			)
			(layer "B.SilkS")
		)
		(fp_line
			(start -1.905 1.0414)
			(end -1.905 -1.0414)
			(stroke
				(width 0.1524)
				(type default)
			)
			(layer "B.SilkS")
		)
		(fp_line
			(start -1.905 -1.0414)
			(end 1.905 -1.0414)
			(stroke
				(width 0.1524)
				(type default)
			)
			(layer "B.SilkS")
		)
		(fp_line
			(start 1.649984 0.824992)
			(end -1.649984 0.824992)
			(stroke
				(width 0.1)
				(type default)
			)
			(layer "B.Fab")
		)
		(fp_line
			(start 1.649984 -0.824992)
			(end 1.649984 0.824992)
			(stroke
				(width 0.1)
				(type default)
			)
			(layer "B.Fab")
		)
		(fp_line
			(start -1.649984 0.824992)
			(end -1.649984 -0.824992)
			(stroke
				(width 0.1)
				(type default)
			)
			(layer "B.Fab")
		)
		(fp_line
			(start -1.649984 -0.824992)
			(end 1.649984 -0.824992)
			(stroke
				(width 0.1)
				(type default)
			)
			(layer "B.Fab")
		)
		(pad "1" smd rect
			(at 1.249934 0)
			(size 1.016 1.8034)
			(layers "B.Cu" "B.Mask" "B.Paste")
			(net "XTAL_CPU0_X32K_X1")
		)
		(pad "2" smd rect
			(at -1.249934 0 180)
			(size 1.016 1.8034)
			(layers "B.Cu" "B.Mask" "B.Paste")
			(net "XTAL_CPU0_X32K_X2")
		)
		(zone
			(layer "B.Cu")
			(hatch none 0.5)
			(connect_pads
				(clearance 0)
			)
			(min_thickness 0.25)
			(keepout
				(tracks not_allowed)
				(vias allowed)
				(pads allowed)
				(copperpour not_allowed)
				(footprints allowed)
			)
			(placement
				(enabled no)
				(sheetname "")
			)
			(fill
				(thermal_gap 0.5)
				(thermal_bridge_width 0.5)
				(island_removal_mode 0)
			)
			(polygon
				(pts
					(xy 400.959828 -315.965078) (xy 400.959828 -317.870078) (xy 402.342096 -317.870078) (xy 402.342096 -315.965078)
				)
			)
		)
	)
	(footprint ""
		(layer "B.Cu")
		(at 389.731758 -321.179952)
		(property "Reference" "R469"
			(at 0 0 0)
			(layer "B.SilkS")
			(hide yes)
			(effects
				(font
					(size 1.27 1.27)
				)
				(justify mirror)
			)
		)
		(property "Value" ""
			(at 0 0 0)
			(layer "B.Fab")
			(effects
				(font
					(size 1.27 1.27)
				)
				(justify mirror)
			)
		)
		(duplicate_pad_numbers_are_jumpers no)
		(fp_line
			(start -0.7874 -0.4064)
			(end -0.7874 0.4064)
			(stroke
				(width 0.1524)
				(type default)
			)
			(layer "B.SilkS")
		)
		(fp_line
			(start -0.7874 0.4064)
			(end 0.7874 0.4064)
			(stroke
				(width 0.1524)
				(type default)
			)
			(layer "B.SilkS")
		)
		(fp_line
			(start 0.7874 -0.4064)
			(end -0.7874 -0.4064)
			(stroke
				(width 0.1524)
				(type default)
			)
			(layer "B.SilkS")
		)
		(fp_line
			(start 0.7874 0.4064)
			(end 0.7874 -0.4064)
			(stroke
				(width 0.1524)
				(type default)
			)
			(layer "B.SilkS")
		)
		(fp_line
			(start -0.67945 -0.3048)
			(end -0.67945 0.3048)
			(stroke
				(width 0.1)
				(type default)
			)
			(layer "B.Fab")
		)
		(fp_line
			(start -0.67945 0.3048)
			(end -0.120396 0.3048)
			(stroke
				(width 0.1)
				(type default)
			)
			(layer "B.Fab")
		)
		(fp_line
			(start -0.12065 -0.3048)
			(end -0.67945 -0.3048)
			(stroke
				(width 0.1)
				(type default)
			)
			(layer "B.Fab")
		)
		(fp_line
			(start -0.12065 -0.2794)
			(end -0.12065 -0.3048)
			(stroke
				(width 0.1)
				(type default)
			)
			(layer "B.Fab")
		)
		(fp_line
			(start -0.120396 0.2794)
			(end 0.12065 0.2794)
			(stroke
				(width 0.1)
				(type default)
			)
			(layer "B.Fab")
		)
		(fp_line
			(start -0.120396 0.3048)
			(end -0.120396 0.2794)
			(stroke
				(width 0.1)
				(type default)
			)
			(layer "B.Fab")
		)
		(fp_line
			(start 0.12065 -0.305054)
			(end 0.12065 -0.2794)
			(stroke
				(width 0.1)
				(type default)
			)
			(layer "B.Fab")
		)
		(fp_line
			(start 0.12065 -0.2794)
			(end -0.12065 -0.2794)
			(stroke
				(width 0.1)
				(type default)
			)
			(layer "B.Fab")
		)
		(fp_line
			(start 0.12065 0.2794)
			(end 0.12065 0.3048)
			(stroke
				(width 0.1)
				(type default)
			)
			(layer "B.Fab")
		)
		(fp_line
			(start 0.12065 0.3048)
			(end 0.67945 0.3048)
			(stroke
				(width 0.1)
				(type default)
			)
			(layer "B.Fab")
		)
		(fp_line
			(start 0.67945 -0.305054)
			(end 0.12065 -0.305054)
			(stroke
				(width 0.1)
				(type default)
			)
			(layer "B.Fab")
		)
		(fp_line
			(start 0.67945 0.3048)
			(end 0.67945 -0.305054)
			(stroke
				(width 0.1)
				(type default)
			)
			(layer "B.Fab")
		)
		(pad "1" smd circle
			(at 0.40005 0 180)
			(size 0 0)
			(layers "B.Cu" "B.Mask" "B.Paste")
			(net "ESPI_CPU0_D1")
		)
		(pad "2" smd circle
			(at -0.40005 0 180)
			(size 0 0)
			(layers "B.Cu" "B.Mask" "B.Paste")
			(net "ESPI_CPU0_R_D1")
		)
	)
)
